(kicad_pcb
	(version 20260206)
	(generator "pcbnew")
	(generator_version "10.0")
	(general
		(thickness 1.6)
		(legacy_teardrops no)
	)
	(paper "A4")
	(title_block
		(title "01162023_DA0F0TEBIF0_F0T_Expander_BD_F_brd_V02_OCP.brd")
		(comment 1 "Grand Teton / footprints 5345-5350 of 9728")
	)
	(layers
		(0 "F.Cu" signal "TOP")
		(4 "In1.Cu" signal "GND")
		(6 "In2.Cu" signal "VCC")
		(8 "In3.Cu" signal "VCC1")
		(10 "In4.Cu" signal "GND1")
		(12 "In5.Cu" signal "IN1")
		(14 "In6.Cu" signal "GND2")
		(16 "In7.Cu" signal "IN2")
		(18 "In8.Cu" signal "GND3")
		(20 "In9.Cu" signal "IN3")
		(22 "In10.Cu" signal "GND4")
		(24 "In11.Cu" signal "IN4")
		(26 "In12.Cu" signal "GND5")
		(28 "In13.Cu" signal "IN5")
		(30 "In14.Cu" signal "GND6")
		(32 "In15.Cu" signal "IN6")
		(34 "In16.Cu" signal "GND7")
		(2 "B.Cu" signal "BOTTOM")
		(9 "F.Adhes" user "F.Adhesive")
		(11 "B.Adhes" user "B.Adhesive")
		(13 "F.Paste" user "Package Geometry/Pastemask Top")
		(15 "B.Paste" user "Package Geometry/Pastemask Bottom")
		(5 "F.SilkS" user "Ref Des/Silkscreen Top")
		(7 "B.SilkS" user "Ref Des/Silkscreen Bottom")
		(1 "F.Mask" user "Board Geometry/Soldermask Top")
		(3 "B.Mask" user "Board Geometry/Soldermask Bottom")
		(17 "Dwgs.User" user "User.Drawings")
		(19 "Cmts.User" user "User.Comments")
		(21 "Eco1.User" user "User.Eco1")
		(23 "Eco2.User" user "User.Eco2")
		(25 "Edge.Cuts" user "Board Geometry/Outline")
		(27 "Margin" user)
		(31 "F.CrtYd" user "Package Geometry/Place Bound Top")
		(29 "B.CrtYd" user "Package Geometry/Place Bound Bottom")
		(35 "F.Fab" user "Ref Des/Assembly Top")
		(33 "B.Fab" user "Ref Des/Assembly Bottom")
	)
	(footprint ""
		(layer "F.Cu")
		(at 109.87405 -160.772094 180)
		(property "Reference" "PU5"
			(at -4.45262 -3.050032 0)
			(unlocked yes)
			(layer "F.SilkS")
			(effects
				(font
					(size 0.7874 0.5842)
					(thickness 0.1524)
				)
				(justify left)
			)
		)
		(property "Value" ""
			(at 0 0 180)
			(layer "F.Fab")
			(effects
				(font
					(size 1.27 1.27)
				)
			)
		)
		(duplicate_pad_numbers_are_jumpers no)
		(fp_line
			(start 1.549908 2.050034)
			(end 1.549908 1.9304)
			(stroke
				(width 0.1524)
				(type default)
			)
			(layer "F.SilkS")
		)
		(fp_line
			(start 1.549908 -1.9812)
			(end 1.549908 -2.050034)
			(stroke
				(width 0.1524)
				(type default)
			)
			(layer "F.SilkS")
		)
		(fp_line
			(start 1.549908 -2.050034)
			(end 0.5842 -2.050034)
			(stroke
				(width 0.1524)
				(type default)
			)
			(layer "F.SilkS")
		)
		(fp_line
			(start 0.3048 -2.4638)
			(end 0.3048 -3.2258)
			(stroke
				(width 0.1524)
				(type default)
			)
			(layer "F.SilkS")
		)
		(fp_line
			(start 0 2.050034)
			(end 1.549908 2.050034)
			(stroke
				(width 0.1524)
				(type default)
			)
			(layer "F.SilkS")
		)
		(fp_line
			(start -0.3048 2.4638)
			(end -0.3048 3.2258)
			(stroke
				(width 0.1524)
				(type default)
			)
			(layer "F.SilkS")
		)
		(fp_line
			(start -0.5842 -2.050034)
			(end -1.549908 -2.050034)
			(stroke
				(width 0.1524)
				(type default)
			)
			(layer "F.SilkS")
		)
		(fp_line
			(start -1.549908 2.050034)
			(end -0.5842 2.050034)
			(stroke
				(width 0.1524)
				(type default)
			)
			(layer "F.SilkS")
		)
		(fp_line
			(start -1.549908 1.9812)
			(end -1.549908 2.050034)
			(stroke
				(width 0.1524)
				(type default)
			)
			(layer "F.SilkS")
		)
		(fp_line
			(start -1.549908 -2.050034)
			(end -1.549908 -1.9812)
			(stroke
				(width 0.1524)
				(type default)
			)
			(layer "F.SilkS")
		)
		(fp_line
			(start -1.9812 0)
			(end -2.3622 0)
			(stroke
				(width 0.1524)
				(type default)
			)
			(layer "F.SilkS")
		)
		(fp_poly
			(pts
				(xy -2.9464 -2.208022) (xy -2.9464 -1.192022) (xy -1.9304 -1.700022)
			)
			(stroke
				(width 0)
				(type default)
			)
			(fill yes)
			(layer "F.SilkS")
		)
		(fp_line
			(start 1.549908 2.050034)
			(end 1.549908 -2.050034)
			(stroke
				(width 0.1)
				(type default)
			)
			(layer "F.Fab")
		)
		(fp_line
			(start 1.549908 -2.050034)
			(end -1.549908 -2.050034)
			(stroke
				(width 0.1)
				(type default)
			)
			(layer "F.Fab")
		)
		(fp_line
			(start 0.3048 -2.4638)
			(end 0.3048 -3.2258)
			(stroke
				(width 0.1)
				(type default)
			)
			(layer "F.Fab")
		)
		(fp_line
			(start -0.3048 2.4638)
			(end -0.3048 3.2258)
			(stroke
				(width 0.1)
				(type default)
			)
			(layer "F.Fab")
		)
		(fp_line
			(start -1.549908 2.050034)
			(end 1.549908 2.050034)
			(stroke
				(width 0.1)
				(type default)
			)
			(layer "F.Fab")
		)
		(fp_line
			(start -1.549908 -2.050034)
			(end -1.549908 2.050034)
			(stroke
				(width 0.1)
				(type default)
			)
			(layer "F.Fab")
		)
		(fp_line
			(start -1.9812 0)
			(end -2.3622 0)
			(stroke
				(width 0.1)
				(type default)
			)
			(layer "F.Fab")
		)
		(fp_poly
			(pts
				(xy -2.9464 -2.208022) (xy -2.9464 -1.192022) (xy -1.9304 -1.700022)
			)
			(stroke
				(width 0)
				(type default)
			)
			(fill yes)
			(layer "F.Fab")
		)
		(fp_text user "11_18"
			(at 2.512568 0.9906 90)
			(unlocked yes)
			(layer "F.SilkS")
			(effects
				(font
					(size 0.635 0.4064)
					(thickness 0.1524)
				)
			)
		)
		(fp_text user "19"
			(at 1.970786 -2.617724 90)
			(unlocked yes)
			(layer "F.SilkS")
			(effects
				(font
					(size 0.635 0.4064)
					(thickness 0.1524)
				)
			)
		)
		(fp_text user "9"
			(at -2.338832 2.0574 90)
			(unlocked yes)
			(layer "F.SilkS")
			(effects
				(font
					(size 0.635 0.4064)
					(thickness 0.1524)
				)
			)
		)
		(fp_text user "11_18"
			(at 2.512568 0.9906 90)
			(unlocked yes)
			(layer "F.Fab")
			(effects
				(font
					(size 0.635 0.4064)
					(thickness 0.1524)
				)
			)
		)
		(fp_text user "19"
			(at 2.410968 -2.159 90)
			(unlocked yes)
			(layer "F.Fab")
			(effects
				(font
					(size 0.635 0.4064)
					(thickness 0.1524)
				)
			)
		)
		(fp_text user "9"
			(at -2.338832 2.0574 90)
			(unlocked yes)
			(layer "F.Fab")
			(effects
				(font
					(size 0.635 0.4064)
					(thickness 0.1524)
				)
			)
		)
		(pad "1" smd rect
			(at -1.35001 -1.700022 270)
			(size 0.3048 0.9144)
			(layers "F.Cu" "F.Mask" "F.Paste")
			(net "SW_P3V3_AUX_BT")
		)
		(pad "2" smd rect
			(at -1.400048 -1.199896 270)
			(size 0.1778 0.8128)
			(layers "F.Cu" "F.Mask" "F.Paste")
			(net "GND")
		)
		(pad "3" smd rect
			(at -1.400048 -0.8001 270)
			(size 0.1778 0.8128)
			(layers "F.Cu" "F.Mask" "F.Paste")
			(net "P3V3_AUX_CS")
		)
		(pad "4" smd rect
			(at -1.400048 -0.40005 270)
			(size 0.1778 0.8128)
			(layers "F.Cu" "F.Mask" "F.Paste")
			(net "GND")
		)
		(pad "5" smd rect
			(at -1.400048 0 270)
			(size 0.1778 0.8128)
			(layers "F.Cu" "F.Mask" "F.Paste")
			(net "P3V3_AUX_REF")
		)
		(pad "6" smd rect
			(at -1.400048 0.40005 270)
			(size 0.1778 0.8128)
			(layers "F.Cu" "F.Mask" "F.Paste")
			(net "GND")
		)
		(pad "7" smd rect
			(at -1.400048 0.8001 270)
			(size 0.1778 0.8128)
			(layers "F.Cu" "F.Mask" "F.Paste")
			(net "P3V3_AUX_FB")
		)
		(pad "8" smd rect
			(at -1.400048 1.199896 270)
			(size 0.1778 0.8128)
			(layers "F.Cu" "F.Mask" "F.Paste")
			(net "P3V3_AUX_EN")
		)
		(pad "9" smd rect
			(at -1.400048 1.700022 270)
			(size 0.3048 0.8128)
			(layers "F.Cu" "F.Mask" "F.Paste")
			(net "PWRGD_P3V3_AUX")
		)
		(pad "10" smd rect
			(at -0.299974 1.299972 180)
			(size 0.3048 2.0066)
			(layers "F.Cu" "F.Mask" "F.Paste")
			(net "SW_P12V_P3V3_AUX_FLT")
		)
		(pad "11_18" smd circle
			(at 1.175004 0.275082 180)
			(size 0 0)
			(layers "F.Cu" "F.Mask" "F.Paste")
			(net "GND")
		)
		(pad "19" smd rect
			(at 1.400048 -1.700022 90)
			(size 0.3048 0.8128)
			(layers "F.Cu" "F.Mask" "F.Paste")
			(net "P3V3_AUX_VCC")
		)
		(pad "20" smd rect
			(at 0.299974 -1.299972 180)
			(size 0.3048 2.0066)
			(layers "F.Cu" "F.Mask" "F.Paste")
			(net "SW_P3V3_AUX_PH")
		)
		(pad "21" smd rect
			(at -0.299974 -1.299972 180)
			(size 0.3048 2.0066)
			(layers "F.Cu" "F.Mask" "F.Paste")
			(net "SW_P12V_P3V3_AUX_FLT")
		)
	)
	(footprint ""
		(layer "F.Cu")
		(at 466.762846 -526.370296 180)
		(property "Reference" "SCREW_SSD5_1"
			(at -5.207 -1.402334 0)
			(unlocked yes)
			(layer "B.SilkS")
			(effects
				(font
					(size 0.7874 0.5842)
					(thickness 0.1524)
				)
				(justify mirror)
			)
		)
		(property "Value" ""
			(at 0 0 180)
			(layer "F.Fab")
			(effects
				(font
					(size 1.27 1.27)
				)
			)
		)
		(duplicate_pad_numbers_are_jumpers no)
		(pad "1" thru_hole circle
			(at 0 0 180)
			(size 0.4572 0.4572)
			(drill 0.2032)
			(layers "*.Cu" "*.Mask")
			(remove_unused_layers no)
			(net "Net_9134")
			(clearance 0.127)
			(thermal_gap 0.127)
			(padstack
				(mode front_inner_back)
				(layer "Inner"
					(shape circle)
					(size 0.4572 0.4572)
					(clearance 0.127)
				)
				(layer "B.Cu"
					(shape circle)
					(size 0.508 0.508)
					(clearance 0.1016)
				)
			)
		)
	)
	(footprint ""
		(layer "F.Cu")
		(at 378.453396 -281.789632)
		(property "Reference" "L144"
			(at 0 0 0)
			(layer "F.SilkS")
			(hide yes)
			(effects
				(font
					(size 1.27 1.27)
				)
			)
		)
		(property "Value" ""
			(at 0 0 0)
			(layer "F.Fab")
			(effects
				(font
					(size 1.27 1.27)
				)
			)
		)
		(duplicate_pad_numbers_are_jumpers no)
		(fp_line
			(start -1.63576 -0.8128)
			(end -1.63576 0.8128)
			(stroke
				(width 0.1524)
				(type default)
			)
			(layer "F.SilkS")
		)
		(fp_line
			(start -1.63576 -0.8128)
			(end 1.63576 -0.8128)
			(stroke
				(width 0.1524)
				(type default)
			)
			(layer "F.SilkS")
		)
		(fp_line
			(start 1.63576 -0.8128)
			(end 1.63576 0.8128)
			(stroke
				(width 0.1524)
				(type default)
			)
			(layer "F.SilkS")
		)
		(fp_line
			(start 1.63576 0.8128)
			(end -1.63576 0.8128)
			(stroke
				(width 0.1524)
				(type default)
			)
			(layer "F.SilkS")
		)
		(fp_line
			(start -1.56083 -0.738632)
			(end -1.56083 0.7366)
			(stroke
				(width 0.1)
				(type default)
			)
			(layer "F.Fab")
		)
		(fp_line
			(start -1.56083 0.7366)
			(end -1.524 0.7366)
			(stroke
				(width 0.1)
				(type default)
			)
			(layer "F.Fab")
		)
		(fp_line
			(start -1.524 0.7366)
			(end 1.524 0.7366)
			(stroke
				(width 0.1)
				(type default)
			)
			(layer "F.Fab")
		)
		(fp_line
			(start 1.524 0.7366)
			(end 1.560576 0.7366)
			(stroke
				(width 0.1)
				(type default)
			)
			(layer "F.Fab")
		)
		(fp_line
			(start 1.560576 -0.738632)
			(end -1.56083 -0.738632)
			(stroke
				(width 0.1)
				(type default)
			)
			(layer "F.Fab")
		)
		(fp_line
			(start 1.560576 0.7366)
			(end 1.560576 -0.738632)
			(stroke
				(width 0.1)
				(type default)
			)
			(layer "F.Fab")
		)
		(pad "1" smd rect
			(at -0.94996 0 180)
			(size 1.1176 1.3716)
			(layers "F.Cu" "F.Mask" "F.Paste")
			(net "P1V8_PLL0_PEX3")
		)
		(pad "2" smd rect
			(at 0.94996 0 180)
			(size 1.1176 1.3716)
			(layers "F.Cu" "F.Mask" "F.Paste")
			(net "SYSPLL_VDDA18_PEX3")
		)
	)
	(footprint ""
		(layer "F.Cu")
		(at 30.847792 -40.037258 90)
		(property "Reference" "U364"
			(at 0.196342 2.376678 90)
			(unlocked yes)
			(layer "F.SilkS")
			(effects
				(font
					(size 0.7874 0.5842)
					(thickness 0.1524)
				)
			)
		)
		(property "Value" ""
			(at 0 0 90)
			(layer "F.Fab")
			(effects
				(font
					(size 1.27 1.27)
				)
			)
		)
		(duplicate_pad_numbers_are_jumpers no)
		(fp_line
			(start -1.949958 -1.610106)
			(end 1.949958 -1.610106)
			(stroke
				(width 0.1524)
				(type default)
			)
			(layer "F.SilkS")
		)
		(fp_line
			(start 1.949958 -1.560068)
			(end 1.949958 1.610106)
			(stroke
				(width 0.1524)
				(type default)
			)
			(layer "F.SilkS")
		)
		(fp_line
			(start 1.949958 1.610106)
			(end -1.949958 1.610106)
			(stroke
				(width 0.1524)
				(type default)
			)
			(layer "F.SilkS")
		)
		(fp_line
			(start -1.949958 1.610106)
			(end -1.949958 -1.610106)
			(stroke
				(width 0.1524)
				(type default)
			)
			(layer "F.SilkS")
		)
		(fp_line
			(start 0.750062 -1.560068)
			(end 0.750062 1.560068)
			(stroke
				(width 0.1)
				(type default)
			)
			(layer "F.Fab")
		)
		(fp_line
			(start -0.750062 -1.560068)
			(end 0.750062 -1.560068)
			(stroke
				(width 0.1)
				(type default)
			)
			(layer "F.Fab")
		)
		(fp_line
			(start 0.750062 1.560068)
			(end -0.750062 1.560068)
			(stroke
				(width 0.1)
				(type default)
			)
			(layer "F.Fab")
		)
		(fp_line
			(start -0.750062 1.560068)
			(end -0.750062 -1.560068)
			(stroke
				(width 0.1)
				(type default)
			)
			(layer "F.Fab")
		)
		(pad "D" smd rect
			(at 1.100074 0)
			(size 1.016 1.4224)
			(layers "F.Cu" "F.Mask" "F.Paste")
			(net "SSD1_AUX_P3V3_EN")
		)
		(pad "G" smd rect
			(at -1.100074 -0.94996)
			(size 1.016 1.4224)
			(layers "F.Cu" "F.Mask" "F.Paste")
			(net "PRSNT_SSD1_R1_N")
		)
		(pad "S" smd rect
			(at -1.100074 0.94996)
			(size 1.016 1.4224)
			(layers "F.Cu" "F.Mask" "F.Paste")
			(net "GND")
		)
	)
	(footprint ""
		(layer "F.Cu")
		(at 411.77083 -137.848848 180)
		(property "Reference" "R362"
			(at 0 0 180)
			(layer "F.SilkS")
			(hide yes)
			(effects
				(font
					(size 1.27 1.27)
				)
			)
		)
		(property "Value" ""
			(at 0 0 180)
			(layer "F.Fab")
			(effects
				(font
					(size 1.27 1.27)
				)
			)
		)
		(duplicate_pad_numbers_are_jumpers no)
		(fp_line
			(start 0.7874 0.4064)
			(end -0.7874 0.4064)
			(stroke
				(width 0.1524)
				(type default)
			)
			(layer "F.SilkS")
		)
		(fp_line
			(start 0.7874 -0.4064)
			(end 0.7874 0.4064)
			(stroke
				(width 0.1524)
				(type default)
			)
			(layer "F.SilkS")
		)
		(fp_line
			(start -0.7874 0.4064)
			(end -0.7874 -0.4064)
			(stroke
				(width 0.1524)
				(type default)
			)
			(layer "F.SilkS")
		)
		(fp_line
			(start -0.7874 -0.4064)
			(end 0.7874 -0.4064)
			(stroke
				(width 0.1524)
				(type default)
			)
			(layer "F.SilkS")
		)
		(fp_line
			(start 0.67945 0.3048)
			(end 0.120396 0.3048)
			(stroke
				(width 0.1)
				(type default)
			)
			(layer "F.Fab")
		)
		(fp_line
			(start 0.67945 -0.3048)
			(end 0.67945 0.3048)
			(stroke
				(width 0.1)
				(type default)
			)
			(layer "F.Fab")
		)
		(fp_line
			(start 0.12065 -0.2794)
			(end 0.12065 -0.3048)
			(stroke
				(width 0.1)
				(type default)
			)
			(layer "F.Fab")
		)
		(fp_line
			(start 0.12065 -0.3048)
			(end 0.67945 -0.3048)
			(stroke
				(width 0.1)
				(type default)
			)
			(layer "F.Fab")
		)
		(fp_line
			(start 0.120396 0.3048)
			(end 0.120396 0.2794)
			(stroke
				(width 0.1)
				(type default)
			)
			(layer "F.Fab")
		)
		(fp_line
			(start 0.120396 0.2794)
			(end -0.12065 0.2794)
			(stroke
				(width 0.1)
				(type default)
			)
			(layer "F.Fab")
		)
		(fp_line
			(start -0.12065 0.3048)
			(end -0.67945 0.3048)
			(stroke
				(width 0.1)
				(type default)
			)
			(layer "F.Fab")
		)
		(fp_line
			(start -0.12065 0.2794)
			(end -0.12065 0.3048)
			(stroke
				(width 0.1)
				(type default)
			)
			(layer "F.Fab")
		)
		(fp_line
			(start -0.12065 -0.2794)
			(end 0.12065 -0.2794)
			(stroke
				(width 0.1)
				(type default)
			)
			(layer "F.Fab")
		)
		(fp_line
			(start -0.12065 -0.305054)
			(end -0.12065 -0.2794)
			(stroke
				(width 0.1)
				(type default)
			)
			(layer "F.Fab")
		)
		(fp_line
			(start -0.67945 0.3048)
			(end -0.67945 -0.305054)
			(stroke
				(width 0.1)
				(type default)
			)
			(layer "F.Fab")
		)
		(fp_line
			(start -0.67945 -0.305054)
			(end -0.12065 -0.305054)
			(stroke
				(width 0.1)
				(type default)
			)
			(layer "F.Fab")
		)
		(pad "1" smd circle
			(at -0.40005 0 180)
			(size 0 0)
			(layers "F.Cu" "F.Mask" "F.Paste")
			(net "PRSNTB1_NIC7_N")
		)
		(pad "2" smd circle
			(at 0.40005 0 180)
			(size 0 0)
			(layers "F.Cu" "F.Mask" "F.Paste")
			(net "P3V3_AUX")
		)
	)
	(footprint ""
		(layer "F.Cu")
		(at 63.47079 -138.864848)
		(property "Reference" "R91"
			(at 0 0 0)
			(layer "F.SilkS")
			(hide yes)
			(effects
				(font
					(size 1.27 1.27)
				)
			)
		)
		(property "Value" ""
			(at 0 0 0)
			(layer "F.Fab")
			(effects
				(font
					(size 1.27 1.27)
				)
			)
		)
		(duplicate_pad_numbers_are_jumpers no)
		(fp_line
			(start -0.7874 -0.4064)
			(end 0.7874 -0.4064)
			(stroke
				(width 0.1524)
				(type default)
			)
			(layer "F.SilkS")
		)
		(fp_line
			(start -0.7874 0.4064)
			(end -0.7874 -0.4064)
			(stroke
				(width 0.1524)
				(type default)
			)
			(layer "F.SilkS")
		)
		(fp_line
			(start 0.7874 -0.4064)
			(end 0.7874 0.4064)
			(stroke
				(width 0.1524)
				(type default)
			)
			(layer "F.SilkS")
		)
		(fp_line
			(start 0.7874 0.4064)
			(end -0.7874 0.4064)
			(stroke
				(width 0.1524)
				(type default)
			)
			(layer "F.SilkS")
		)
		(fp_line
			(start -0.67945 -0.305054)
			(end -0.12065 -0.305054)
			(stroke
				(width 0.1)
				(type default)
			)
			(layer "F.Fab")
		)
		(fp_line
			(start -0.67945 0.3048)
			(end -0.67945 -0.305054)
			(stroke
				(width 0.1)
				(type default)
			)
			(layer "F.Fab")
		)
		(fp_line
			(start -0.12065 -0.305054)
			(end -0.12065 -0.2794)
			(stroke
				(width 0.1)
				(type default)
			)
			(layer "F.Fab")
		)
		(fp_line
			(start -0.12065 -0.2794)
			(end 0.12065 -0.2794)
			(stroke
				(width 0.1)
				(type default)
			)
			(layer "F.Fab")
		)
		(fp_line
			(start -0.12065 0.2794)
			(end -0.12065 0.3048)
			(stroke
				(width 0.1)
				(type default)
			)
			(layer "F.Fab")
		)
		(fp_line
			(start -0.12065 0.3048)
			(end -0.67945 0.3048)
			(stroke
				(width 0.1)
				(type default)
			)
			(layer "F.Fab")
		)
		(fp_line
			(start 0.120396 0.2794)
			(end -0.12065 0.2794)
			(stroke
				(width 0.1)
				(type default)
			)
			(layer "F.Fab")
		)
		(fp_line
			(start 0.120396 0.3048)
			(end 0.120396 0.2794)
			(stroke
				(width 0.1)
				(type default)
			)
			(layer "F.Fab")
		)
		(fp_line
			(start 0.12065 -0.3048)
			(end 0.67945 -0.3048)
			(stroke
				(width 0.1)
				(type default)
			)
			(layer "F.Fab")
		)
		(fp_line
			(start 0.12065 -0.2794)
			(end 0.12065 -0.3048)
			(stroke
				(width 0.1)
				(type default)
			)
			(layer "F.Fab")
		)
		(fp_line
			(start 0.67945 -0.3048)
			(end 0.67945 0.3048)
			(stroke
				(width 0.1)
				(type default)
			)
			(layer "F.Fab")
		)
		(fp_line
			(start 0.67945 0.3048)
			(end 0.120396 0.3048)
			(stroke
				(width 0.1)
				(type default)
			)
			(layer "F.Fab")
		)
		(pad "1" smd circle
			(at -0.40005 0)
			(size 0 0)
			(layers "F.Cu" "F.Mask" "F.Paste")
			(net "PRSNT_NIC1_N")
		)
		(pad "2" smd circle
			(at 0.40005 0)
			(size 0 0)
			(layers "F.Cu" "F.Mask" "F.Paste")
			(net "PRSNTB1_NIC1_N")
		)
	)
)
